(kicad_pcb
	(version 20260206)
	(generator "pcbnew")
	(generator_version "10.0")
	(general
		(thickness 1.6)
		(legacy_teardrops no)
	)
	(paper "A4")
	(title_block
		(title "v2-tray-backplane — ms_tbp_v2.brd")
		(comment 1 "Open CloudServer (Microsoft) / footprints 140-145 of 164")
	)
	(layers
		(0 "F.Cu" signal "TOP")
		(4 "In1.Cu" signal "LYR2")
		(6 "In2.Cu" signal "LYR3")
		(8 "In3.Cu" signal "LYR4")
		(10 "In4.Cu" signal "LYR5")
		(12 "In5.Cu" signal "LYR6")
		(14 "In6.Cu" signal "LYR7")
		(2 "B.Cu" signal "BOTTOM")
		(9 "F.Adhes" user "F.Adhesive")
		(11 "B.Adhes" user "B.Adhesive")
		(13 "F.Paste" user "Package Geometry/Pastemask Top")
		(15 "B.Paste" user "Package Geometry/Pastemask Bottom")
		(5 "F.SilkS" user "Ref Des/Silkscreen Top")
		(7 "B.SilkS" user "Ref Des/Silkscreen Bottom")
		(1 "F.Mask" user "Board Geometry/Soldermask Top")
		(3 "B.Mask" user "Board Geometry/Soldermask Bottom")
		(17 "Dwgs.User" user "User.Drawings")
		(19 "Cmts.User" user "User.Comments")
		(21 "Eco1.User" user "User.Eco1")
		(23 "Eco2.User" user "User.Eco2")
		(25 "Edge.Cuts" user "Board Geometry/Outline")
		(27 "Margin" user)
		(31 "F.CrtYd" user "Package Geometry/Place Bound Top")
		(29 "B.CrtYd" user "Package Geometry/Place Bound Bottom")
		(35 "F.Fab" user "Ref Des/Assembly Top")
		(33 "B.Fab" user "Ref Des/Assembly Bottom")
	)
	(footprint ""
		(layer "F.Cu")
		(at -284.48 45.72)
		(property "Reference" "FB1"
			(at -0.635 1.0541 0)
			(unlocked yes)
			(layer "F.SilkS")
			(effects
				(font
					(size 0.762 0.5334)
					(thickness 0.1016)
				)
				(justify left)
			)
		)
		(property "Value" ""
			(at 0 0 0)
			(layer "F.Fab")
			(effects
				(font
					(size 1.27 1.27)
				)
			)
		)
		(duplicate_pad_numbers_are_jumpers no)
		(fp_poly
			(pts
				(xy -1.016 0.508) (xy -1.016 -0.508) (xy 1.016 -0.508) (xy 1.016 0.508)
			)
			(stroke
				(width 0)
				(type default)
			)
			(fill no)
			(layer "F.CrtYd")
		)
		(fp_line
			(start -0.508 -0.254)
			(end 0.508 -0.254)
			(stroke
				(width 0.1)
				(type default)
			)
			(layer "F.Fab")
		)
		(fp_line
			(start -0.508 0.254)
			(end -0.508 -0.254)
			(stroke
				(width 0.1)
				(type default)
			)
			(layer "F.Fab")
		)
		(fp_line
			(start 0.508 -0.254)
			(end 0.508 0.254)
			(stroke
				(width 0.1)
				(type default)
			)
			(layer "F.Fab")
		)
		(fp_line
			(start 0.508 0.254)
			(end -0.508 0.254)
			(stroke
				(width 0.1)
				(type default)
			)
			(layer "F.Fab")
		)
		(pad "1" smd rect
			(at -0.4572 0 90)
			(size 0.508 0.5842)
			(layers "F.Cu" "F.Mask" "F.Paste")
			(net "UNNAMED_4_FERRITE_I148_A")
		)
		(pad "2" smd rect
			(at 0.4572 0 90)
			(size 0.508 0.5842)
			(layers "F.Cu" "F.Mask" "F.Paste")
			(net "P3V3_10G_B1_VCCR")
		)
	)
	(footprint ""
		(layer "F.Cu")
		(at -45.250001 7.582002 180)
		(property "Reference" "FB5"
			(at -2.451001 0.050902 0)
			(unlocked yes)
			(layer "F.SilkS")
			(effects
				(font
					(size 0.762 0.5334)
					(thickness 0.1016)
				)
				(justify left)
			)
		)
		(property "Value" ""
			(at 0 0 180)
			(layer "F.Fab")
			(effects
				(font
					(size 1.27 1.27)
				)
			)
		)
		(duplicate_pad_numbers_are_jumpers no)
		(fp_poly
			(pts
				(xy -1.016 0.508) (xy -1.016 -0.508) (xy 1.016 -0.508) (xy 1.016 0.508)
			)
			(stroke
				(width 0)
				(type default)
			)
			(fill no)
			(layer "F.CrtYd")
		)
		(fp_line
			(start 0.508 0.254)
			(end -0.508 0.254)
			(stroke
				(width 0.1)
				(type default)
			)
			(layer "F.Fab")
		)
		(fp_line
			(start 0.508 -0.254)
			(end 0.508 0.254)
			(stroke
				(width 0.1)
				(type default)
			)
			(layer "F.Fab")
		)
		(fp_line
			(start -0.508 0.254)
			(end -0.508 -0.254)
			(stroke
				(width 0.1)
				(type default)
			)
			(layer "F.Fab")
		)
		(fp_line
			(start -0.508 -0.254)
			(end 0.508 -0.254)
			(stroke
				(width 0.1)
				(type default)
			)
			(layer "F.Fab")
		)
		(pad "1" smd rect
			(at -0.4572 0 270)
			(size 0.508 0.5842)
			(layers "F.Cu" "F.Mask" "F.Paste")
			(net "UNNAMED_8_FERRITE_I51_A")
		)
		(pad "2" smd rect
			(at 0.4572 0 270)
			(size 0.508 0.5842)
			(layers "F.Cu" "F.Mask" "F.Paste")
			(net "P3V3_40G_B2_VCC_TX")
		)
	)
	(footprint ""
		(layer "F.Cu")
		(at -266.192 8.636 180)
		(property "Reference" "R72"
			(at -2.413 -0.1651 0)
			(unlocked yes)
			(layer "F.SilkS")
			(effects
				(font
					(size 0.762 0.5334)
					(thickness 0.1016)
				)
			)
		)
		(property "Value" ""
			(at 0 0 180)
			(layer "F.Fab")
			(effects
				(font
					(size 1.27 1.27)
				)
			)
		)
		(duplicate_pad_numbers_are_jumpers no)
		(fp_line
			(start 0 -0.381)
			(end 0 0.381)
			(stroke
				(width 0.127)
				(type default)
			)
			(layer "F.SilkS")
		)
		(fp_poly
			(pts
				(xy 1.255601 0.656399) (xy -1.255601 0.656399) (xy -1.255601 -0.6564) (xy 1.255601 -0.6564)
			)
			(stroke
				(width 0)
				(type default)
			)
			(fill no)
			(layer "F.CrtYd")
		)
		(fp_line
			(start 0.800001 0.399999)
			(end 0.800001 -0.399999)
			(stroke
				(width 0.1)
				(type default)
			)
			(layer "F.Fab")
		)
		(fp_line
			(start 0.800001 -0.399999)
			(end -0.800001 -0.399999)
			(stroke
				(width 0.1)
				(type default)
			)
			(layer "F.Fab")
		)
		(fp_line
			(start -0.800001 0.399999)
			(end 0.800001 0.399999)
			(stroke
				(width 0.1)
				(type default)
			)
			(layer "F.Fab")
		)
		(fp_line
			(start -0.800001 -0.399999)
			(end -0.800001 0.399999)
			(stroke
				(width 0.1)
				(type default)
			)
			(layer "F.Fab")
		)
		(pad "1" smd rect
			(at -0.650001 0 180)
			(size 0.7112 0.8128)
			(layers "F.Cu" "F.Mask" "F.Paste")
			(net "P3V3_B1_QSFP")
		)
		(pad "2" smd rect
			(at 0.650001 0)
			(size 0.7112 0.8128)
			(layers "F.Cu" "F.Mask" "F.Paste")
			(net "P3V3_40G_B1_VCC_TX")
		)
	)
	(footprint ""
		(layer "F.Cu")
		(at -123.649689 36.82998 180)
		(property "Reference" "J15"
			(at 0 11.834899 0)
			(unlocked yes)
			(layer "F.SilkS")
			(effects
				(font
					(size 0.762 0.5334)
					(thickness 0.1016)
				)
			)
		)
		(property "Value" ""
			(at 0 0 180)
			(layer "F.Fab")
			(effects
				(font
					(size 1.27 1.27)
				)
			)
		)
		(duplicate_pad_numbers_are_jumpers no)
		(fp_line
			(start 5.325001 10.870001)
			(end -5.325001 10.870001)
			(stroke
				(width 0.127)
				(type default)
			)
			(layer "F.SilkS")
		)
		(fp_line
			(start 5.325001 -12.76)
			(end 5.325001 10.870001)
			(stroke
				(width 0.127)
				(type default)
			)
			(layer "F.SilkS")
		)
		(fp_line
			(start 2.775001 -12.76)
			(end 5.325001 -12.76)
			(stroke
				(width 0.127)
				(type default)
			)
			(layer "F.SilkS")
		)
		(fp_line
			(start 2.775001 -42.660001)
			(end 2.775001 -12.76)
			(stroke
				(width 0.127)
				(type default)
			)
			(layer "F.SilkS")
		)
		(fp_line
			(start -2.775001 -12.76)
			(end -2.775001 -42.660001)
			(stroke
				(width 0.127)
				(type default)
			)
			(layer "F.SilkS")
		)
		(fp_line
			(start -2.775001 -42.660001)
			(end 2.775001 -42.660001)
			(stroke
				(width 0.127)
				(type default)
			)
			(layer "F.SilkS")
		)
		(fp_line
			(start -5.325001 10.870001)
			(end -5.325001 -12.76)
			(stroke
				(width 0.127)
				(type default)
			)
			(layer "F.SilkS")
		)
		(fp_line
			(start -5.325001 -12.76)
			(end -2.775001 -12.76)
			(stroke
				(width 0.127)
				(type default)
			)
			(layer "F.SilkS")
		)
		(fp_poly
			(pts
				(arc
					(start -7.3152 0)
					(mid 7.3152 0)
					(end -7.3152 0)
				)
			)
			(stroke
				(width 0)
				(type default)
			)
			(fill no)
			(layer "B.CrtYd")
		)
		(fp_poly
			(pts
				(xy 6.324999 11.869999) (xy -6.324999 11.869999) (xy -6.324999 -13.76) (xy -3.774999 -13.76) (xy -3.774999 -43.659999)
				(xy 3.774999 -43.659999) (xy 3.774999 -13.76) (xy 6.324999 -13.76)
			)
			(stroke
				(width 0)
				(type default)
			)
			(fill no)
			(layer "F.CrtYd")
		)
		(fp_line
			(start 5.325001 10.870001)
			(end -5.325001 10.870001)
			(stroke
				(width 0.1)
				(type default)
			)
			(layer "F.Fab")
		)
		(fp_line
			(start 5.325001 -12.76)
			(end 5.325001 10.870001)
			(stroke
				(width 0.1)
				(type default)
			)
			(layer "F.Fab")
		)
		(fp_line
			(start 2.775001 -12.76)
			(end 5.325001 -12.76)
			(stroke
				(width 0.1)
				(type default)
			)
			(layer "F.Fab")
		)
		(fp_line
			(start 2.775001 -42.660001)
			(end 2.775001 -12.76)
			(stroke
				(width 0.1)
				(type default)
			)
			(layer "F.Fab")
		)
		(fp_line
			(start -2.775001 -12.76)
			(end -2.775001 -42.660001)
			(stroke
				(width 0.1)
				(type default)
			)
			(layer "F.Fab")
		)
		(fp_line
			(start -2.775001 -42.660001)
			(end 2.775001 -42.660001)
			(stroke
				(width 0.1)
				(type default)
			)
			(layer "F.Fab")
		)
		(fp_line
			(start -5.325001 10.870001)
			(end -5.325001 -12.76)
			(stroke
				(width 0.1)
				(type default)
			)
			(layer "F.Fab")
		)
		(fp_line
			(start -5.325001 -12.76)
			(end -2.775001 -12.76)
			(stroke
				(width 0.1)
				(type default)
			)
			(layer "F.Fab")
		)
		(pad "" np_thru_hole circle
			(at 0 -5.629999 180)
			(size 1.27 1.27)
			(drill 3.9624)
			(layers "*.Cu" "*.Mask")
		)
		(pad "" np_thru_hole circle
			(at 0 6.619999 180)
			(size 1.27 1.27)
			(drill 3.9624)
			(layers "*.Cu" "*.Mask")
		)
		(pad "1" thru_hole circle
			(at 0 0 180)
			(size 5.588 5.588)
			(drill 3.9624)
			(layers "*.Cu" "*.Mask")
			(remove_unused_layers no)
			(net "GND")
		)
		(zone
			(layers "F.Cu" "B.Cu" "In1.Cu" "In2.Cu" "In3.Cu" "In4.Cu" "In5.Cu" "In6.Cu")
			(hatch none 0.5)
			(connect_pads
				(clearance 0)
			)
			(min_thickness 0.25)
			(keepout
				(tracks not_allowed)
				(vias allowed)
				(pads allowed)
				(copperpour not_allowed)
				(footprints allowed)
			)
			(placement
				(enabled no)
				(sheetname "")
			)
			(fill
				(thermal_gap 0.5)
				(thermal_bridge_width 0.5)
				(island_removal_mode 0)
			)
			(polygon
				(pts
					(arc
						(start -121.287489 30.20998)
						(mid -126.011889 30.20998)
						(end -121.287489 30.20998)
					)
				)
			)
		)
		(zone
			(layers "F.Cu" "B.Cu" "In1.Cu" "In2.Cu" "In3.Cu" "In4.Cu" "In5.Cu" "In6.Cu")
			(hatch none 0.5)
			(connect_pads
				(clearance 0)
			)
			(min_thickness 0.25)
			(keepout
				(tracks not_allowed)
				(vias allowed)
				(pads allowed)
				(copperpour not_allowed)
				(footprints allowed)
			)
			(placement
				(enabled no)
				(sheetname "")
			)
			(fill
				(thermal_gap 0.5)
				(thermal_bridge_width 0.5)
				(island_removal_mode 0)
			)
			(polygon
				(pts
					(arc
						(start -121.287489 42.459979)
						(mid -126.011889 42.459979)
						(end -121.287489 42.459979)
					)
				)
			)
		)
	)
	(footprint ""
		(layer "F.Cu")
		(at -331.47 11.8618 180)
		(property "Reference" "R77"
			(at -3.21056 0.05334 0)
			(unlocked yes)
			(layer "F.SilkS")
			(effects
				(font
					(size 0.762 0.5334)
					(thickness 0.1016)
				)
			)
		)
		(property "Value" ""
			(at 0 0 180)
			(layer "F.Fab")
			(effects
				(font
					(size 1.27 1.27)
				)
			)
		)
		(duplicate_pad_numbers_are_jumpers no)
		(fp_line
			(start 0 -0.381)
			(end 0 0.381)
			(stroke
				(width 0.127)
				(type default)
			)
			(layer "F.SilkS")
		)
		(fp_poly
			(pts
				(xy 1.255601 0.656399) (xy -1.255601 0.656399) (xy -1.255601 -0.6564) (xy 1.255601 -0.6564)
			)
			(stroke
				(width 0)
				(type default)
			)
			(fill no)
			(layer "F.CrtYd")
		)
		(fp_line
			(start 0.800001 0.399999)
			(end 0.800001 -0.399999)
			(stroke
				(width 0.1)
				(type default)
			)
			(layer "F.Fab")
		)
		(fp_line
			(start 0.800001 -0.399999)
			(end -0.800001 -0.399999)
			(stroke
				(width 0.1)
				(type default)
			)
			(layer "F.Fab")
		)
		(fp_line
			(start -0.800001 0.399999)
			(end 0.800001 0.399999)
			(stroke
				(width 0.1)
				(type default)
			)
			(layer "F.Fab")
		)
		(fp_line
			(start -0.800001 -0.399999)
			(end -0.800001 0.399999)
			(stroke
				(width 0.1)
				(type default)
			)
			(layer "F.Fab")
		)
		(pad "1" smd rect
			(at -0.650001 0 180)
			(size 0.7112 0.8128)
			(layers "F.Cu" "F.Mask" "F.Paste")
			(net "ETH40G_B1_MODSEL_N")
		)
		(pad "2" smd rect
			(at 0.650001 0)
			(size 0.7112 0.8128)
			(layers "F.Cu" "F.Mask" "F.Paste")
			(net "GND")
		)
	)
	(footprint ""
		(layer "F.Cu")
		(at -334.6958 16.891 90)
		(property "Reference" "R84"
			(at -0.254 -1.3081 90)
			(unlocked yes)
			(layer "F.SilkS")
			(effects
				(font
					(size 0.762 0.5334)
					(thickness 0.1016)
				)
			)
		)
		(property "Value" ""
			(at 0 0 90)
			(layer "F.Fab")
			(effects
				(font
					(size 1.27 1.27)
				)
			)
		)
		(duplicate_pad_numbers_are_jumpers no)
		(fp_line
			(start 0 -0.381)
			(end 0 0.381)
			(stroke
				(width 0.127)
				(type default)
			)
			(layer "F.SilkS")
		)
		(fp_poly
			(pts
				(xy 1.255601 0.656399) (xy -1.255601 0.656399) (xy -1.255601 -0.6564) (xy 1.255601 -0.6564)
			)
			(stroke
				(width 0)
				(type default)
			)
			(fill no)
			(layer "F.CrtYd")
		)
		(fp_line
			(start 0.800001 -0.399999)
			(end -0.800001 -0.399999)
			(stroke
				(width 0.1)
				(type default)
			)
			(layer "F.Fab")
		)
		(fp_line
			(start -0.800001 -0.399999)
			(end -0.800001 0.399999)
			(stroke
				(width 0.1)
				(type default)
			)
			(layer "F.Fab")
		)
		(fp_line
			(start 0.800001 0.399999)
			(end 0.800001 -0.399999)
			(stroke
				(width 0.1)
				(type default)
			)
			(layer "F.Fab")
		)
		(fp_line
			(start -0.800001 0.399999)
			(end 0.800001 0.399999)
			(stroke
				(width 0.1)
				(type default)
			)
			(layer "F.Fab")
		)
		(pad "1" smd rect
			(at -0.650001 0 90)
			(size 0.7112 0.8128)
			(layers "F.Cu" "F.Mask" "F.Paste")
			(net "P3V3_B1_QSFP")
		)
		(pad "2" smd rect
			(at 0.650001 0 270)
			(size 0.7112 0.8128)
			(layers "F.Cu" "F.Mask" "F.Paste")
			(net "ETH40G_B1_LPMODE")
		)
	)
)
